(kicad_pcb
	(version 20260206)
	(generator "pcbnew")
	(generator_version "10.0")
	(general
		(thickness 1.6)
		(legacy_teardrops no)
	)
	(paper "A4")
	(title_block
		(title "01162023_DA0F0TEBIF0_F0T_Expander_BD_F_brd_V02_OCP.brd")
		(comment 1 "Grand Teton / footprints 2079-2084 of 9728")
	)
	(layers
		(0 "F.Cu" signal "TOP")
		(4 "In1.Cu" signal "GND")
		(6 "In2.Cu" signal "VCC")
		(8 "In3.Cu" signal "VCC1")
		(10 "In4.Cu" signal "GND1")
		(12 "In5.Cu" signal "IN1")
		(14 "In6.Cu" signal "GND2")
		(16 "In7.Cu" signal "IN2")
		(18 "In8.Cu" signal "GND3")
		(20 "In9.Cu" signal "IN3")
		(22 "In10.Cu" signal "GND4")
		(24 "In11.Cu" signal "IN4")
		(26 "In12.Cu" signal "GND5")
		(28 "In13.Cu" signal "IN5")
		(30 "In14.Cu" signal "GND6")
		(32 "In15.Cu" signal "IN6")
		(34 "In16.Cu" signal "GND7")
		(2 "B.Cu" signal "BOTTOM")
		(9 "F.Adhes" user "F.Adhesive")
		(11 "B.Adhes" user "B.Adhesive")
		(13 "F.Paste" user "Package Geometry/Pastemask Top")
		(15 "B.Paste" user "Package Geometry/Pastemask Bottom")
		(5 "F.SilkS" user "Ref Des/Silkscreen Top")
		(7 "B.SilkS" user "Ref Des/Silkscreen Bottom")
		(1 "F.Mask" user "Board Geometry/Soldermask Top")
		(3 "B.Mask" user "Board Geometry/Soldermask Bottom")
		(17 "Dwgs.User" user "User.Drawings")
		(19 "Cmts.User" user "User.Comments")
		(21 "Eco1.User" user "User.Eco1")
		(23 "Eco2.User" user "User.Eco2")
		(25 "Edge.Cuts" user "Board Geometry/Outline")
		(27 "Margin" user)
		(31 "F.CrtYd" user "Package Geometry/Place Bound Top")
		(29 "B.CrtYd" user "Package Geometry/Place Bound Bottom")
		(35 "F.Fab" user "Ref Des/Assembly Top")
		(33 "B.Fab" user "Ref Des/Assembly Bottom")
	)
	(footprint ""
		(layer "F.Cu")
		(at 135.802878 -225.49993 180)
		(property "Reference" "U320"
			(at 1.589278 -8.367268 0)
			(unlocked yes)
			(layer "F.SilkS")
			(effects
				(font
					(size 0.7874 0.5842)
					(thickness 0.1524)
				)
				(justify left)
			)
		)
		(property "Value" ""
			(at 0 0 180)
			(layer "F.Fab")
			(effects
				(font
					(size 1.27 1.27)
				)
			)
		)
		(duplicate_pad_numbers_are_jumpers no)
		(fp_line
			(start 3.795014 5.2451)
			(end 3.795014 -5.2451)
			(stroke
				(width 0.1524)
				(type default)
			)
			(layer "F.SilkS")
		)
		(fp_line
			(start 3.795014 -5.2451)
			(end 1.9431 -5.2451)
			(stroke
				(width 0.1524)
				(type default)
			)
			(layer "F.SilkS")
		)
		(fp_line
			(start 1.9431 -5.2451)
			(end 0 -3.302)
			(stroke
				(width 0.1524)
				(type default)
			)
			(layer "F.SilkS")
		)
		(fp_line
			(start 0 -3.302)
			(end -1.9431 -5.2451)
			(stroke
				(width 0.1524)
				(type default)
			)
			(layer "F.SilkS")
		)
		(fp_line
			(start -1.9431 -5.2451)
			(end -3.795014 -5.2451)
			(stroke
				(width 0.1524)
				(type default)
			)
			(layer "F.SilkS")
		)
		(fp_line
			(start -3.795014 5.2451)
			(end 3.795014 5.2451)
			(stroke
				(width 0.1524)
				(type default)
			)
			(layer "F.SilkS")
		)
		(fp_line
			(start -3.795014 -5.2451)
			(end -3.795014 5.2451)
			(stroke
				(width 0.1524)
				(type default)
			)
			(layer "F.SilkS")
		)
		(fp_poly
			(pts
				(xy -5.976366 -4.445) (xy -7.239 -3.81381) (xy -7.239 -5.07619)
			)
			(stroke
				(width 0)
				(type default)
			)
			(fill yes)
			(layer "F.SilkS")
		)
		(fp_line
			(start 3.795014 5.2451)
			(end 3.795014 -5.2451)
			(stroke
				(width 0.1)
				(type default)
			)
			(layer "F.Fab")
		)
		(fp_line
			(start 3.795014 -5.2451)
			(end -3.795014 -5.2451)
			(stroke
				(width 0.1)
				(type default)
			)
			(layer "F.Fab")
		)
		(fp_line
			(start -3.795014 5.2451)
			(end 3.795014 5.2451)
			(stroke
				(width 0.1)
				(type default)
			)
			(layer "F.Fab")
		)
		(fp_line
			(start -3.795014 -5.2451)
			(end -3.795014 5.2451)
			(stroke
				(width 0.1)
				(type default)
			)
			(layer "F.Fab")
		)
		(fp_poly
			(pts
				(xy -5.976366 -4.445) (xy -7.239 -3.81381) (xy -7.239 -5.07619)
			)
			(stroke
				(width 0)
				(type default)
			)
			(fill yes)
			(layer "F.Fab")
		)
		(pad "1" smd rect
			(at -4.880102 -4.445 90)
			(size 0.8128 1.905)
			(layers "F.Cu" "F.Mask" "F.Paste")
			(net "SPI_PEX1_SDIO3_R1")
		)
		(pad "2" smd rect
			(at -4.880102 -3.175 90)
			(size 0.8128 1.905)
			(layers "F.Cu" "F.Mask" "F.Paste")
			(net "P1V8_PEX")
		)
		(pad "3" smd rect
			(at -4.880102 -1.905 90)
			(size 0.8128 1.905)
			(layers "F.Cu" "F.Mask" "F.Paste")
			(net "SPI_PEX1_RST_R_N")
		)
		(pad "4" smd rect
			(at -4.880102 -0.635 90)
			(size 0.8128 1.905)
			(layers "F.Cu" "F.Mask" "F.Paste")
			(net "Net_9007")
		)
		(pad "5" smd rect
			(at -4.880102 0.635 90)
			(size 0.8128 1.905)
			(layers "F.Cu" "F.Mask" "F.Paste")
			(net "Net_9006")
		)
		(pad "6" smd rect
			(at -4.880102 1.905 90)
			(size 0.8128 1.905)
			(layers "F.Cu" "F.Mask" "F.Paste")
			(net "Net_9005")
		)
		(pad "7" smd rect
			(at -4.880102 3.175 90)
			(size 0.8128 1.905)
			(layers "F.Cu" "F.Mask" "F.Paste")
			(net "SPI_PEX1_CS_MUX_R_N")
		)
		(pad "8" smd rect
			(at -4.880102 4.445 90)
			(size 0.8128 1.905)
			(layers "F.Cu" "F.Mask" "F.Paste")
			(net "SPI_PEX1_SDIO1_MUX_R")
		)
		(pad "9" smd rect
			(at 4.880102 4.445 270)
			(size 0.8128 1.905)
			(layers "F.Cu" "F.Mask" "F.Paste")
			(net "SPI_PEX1_SDIO2_R1")
		)
		(pad "10" smd rect
			(at 4.880102 3.175 270)
			(size 0.8128 1.905)
			(layers "F.Cu" "F.Mask" "F.Paste")
			(net "GND")
		)
		(pad "11" smd rect
			(at 4.880102 1.905 270)
			(size 0.8128 1.905)
			(layers "F.Cu" "F.Mask" "F.Paste")
			(net "Net_9004")
		)
		(pad "12" smd rect
			(at 4.880102 0.635 270)
			(size 0.8128 1.905)
			(layers "F.Cu" "F.Mask" "F.Paste")
			(net "Net_9003")
		)
		(pad "13" smd rect
			(at 4.880102 -0.635 270)
			(size 0.8128 1.905)
			(layers "F.Cu" "F.Mask" "F.Paste")
			(net "Net_9002")
		)
		(pad "14" smd rect
			(at 4.880102 -1.905 270)
			(size 0.8128 1.905)
			(layers "F.Cu" "F.Mask" "F.Paste")
			(net "Net_9001")
		)
		(pad "15" smd rect
			(at 4.880102 -3.175 270)
			(size 0.8128 1.905)
			(layers "F.Cu" "F.Mask" "F.Paste")
			(net "SPI_PEX1_SDIO0_MUX_R")
		)
		(pad "16" smd rect
			(at 4.880102 -4.445 270)
			(size 0.8128 1.905)
			(layers "F.Cu" "F.Mask" "F.Paste")
			(net "SPI_PEX1_CLK_MUX_R")
		)
	)
	(footprint ""
		(layer "F.Cu")
		(at 241.5794 -213.3854 -90)
		(property "Reference" "C4435"
			(at 0 0 270)
			(layer "F.SilkS")
			(hide yes)
			(effects
				(font
					(size 1.27 1.27)
				)
			)
		)
		(property "Value" ""
			(at 0 0 270)
			(layer "F.Fab")
			(effects
				(font
					(size 1.27 1.27)
				)
			)
		)
		(duplicate_pad_numbers_are_jumpers no)
		(fp_line
			(start -0.7874 0.4064)
			(end -0.7874 -0.4064)
			(stroke
				(width 0.1524)
				(type default)
			)
			(layer "F.SilkS")
		)
		(fp_line
			(start 0.7874 0.4064)
			(end -0.7874 0.4064)
			(stroke
				(width 0.1524)
				(type default)
			)
			(layer "F.SilkS")
		)
		(fp_line
			(start -0.7874 -0.4064)
			(end 0.7874 -0.4064)
			(stroke
				(width 0.1524)
				(type default)
			)
			(layer "F.SilkS")
		)
		(fp_line
			(start 0.7874 -0.4064)
			(end 0.7874 0.4064)
			(stroke
				(width 0.1524)
				(type default)
			)
			(layer "F.SilkS")
		)
		(fp_line
			(start -0.67945 0.3048)
			(end -0.67945 -0.305054)
			(stroke
				(width 0.1)
				(type default)
			)
			(layer "F.Fab")
		)
		(fp_line
			(start -0.12065 0.3048)
			(end -0.67945 0.3048)
			(stroke
				(width 0.1)
				(type default)
			)
			(layer "F.Fab")
		)
		(fp_line
			(start 0.120396 0.3048)
			(end 0.120396 0.2794)
			(stroke
				(width 0.1)
				(type default)
			)
			(layer "F.Fab")
		)
		(fp_line
			(start 0.67945 0.3048)
			(end 0.120396 0.3048)
			(stroke
				(width 0.1)
				(type default)
			)
			(layer "F.Fab")
		)
		(fp_line
			(start -0.12065 0.2794)
			(end -0.12065 0.3048)
			(stroke
				(width 0.1)
				(type default)
			)
			(layer "F.Fab")
		)
		(fp_line
			(start 0.120396 0.2794)
			(end -0.12065 0.2794)
			(stroke
				(width 0.1)
				(type default)
			)
			(layer "F.Fab")
		)
		(fp_line
			(start -0.12065 -0.2794)
			(end 0.12065 -0.2794)
			(stroke
				(width 0.1)
				(type default)
			)
			(layer "F.Fab")
		)
		(fp_line
			(start 0.12065 -0.2794)
			(end 0.12065 -0.3048)
			(stroke
				(width 0.1)
				(type default)
			)
			(layer "F.Fab")
		)
		(fp_line
			(start 0.12065 -0.3048)
			(end 0.67945 -0.3048)
			(stroke
				(width 0.1)
				(type default)
			)
			(layer "F.Fab")
		)
		(fp_line
			(start 0.67945 -0.3048)
			(end 0.67945 0.3048)
			(stroke
				(width 0.1)
				(type default)
			)
			(layer "F.Fab")
		)
		(fp_line
			(start -0.67945 -0.305054)
			(end -0.12065 -0.305054)
			(stroke
				(width 0.1)
				(type default)
			)
			(layer "F.Fab")
		)
		(fp_line
			(start -0.12065 -0.305054)
			(end -0.12065 -0.2794)
			(stroke
				(width 0.1)
				(type default)
			)
			(layer "F.Fab")
		)
		(pad "1" smd circle
			(at -0.40005 0 270)
			(size 0 0)
			(layers "F.Cu" "F.Mask" "F.Paste")
			(net "P1V8_PLL0_PEX1_SCALED")
		)
		(pad "2" smd circle
			(at 0.40005 0 270)
			(size 0 0)
			(layers "F.Cu" "F.Mask" "F.Paste")
			(net "GND")
		)
	)
	(footprint ""
		(layer "F.Cu")
		(at 275.26869 -409.736036 90)
		(property "Reference" "R1818"
			(at 0 0 90)
			(layer "F.SilkS")
			(hide yes)
			(effects
				(font
					(size 1.27 1.27)
				)
			)
		)
		(property "Value" ""
			(at 0 0 90)
			(layer "F.Fab")
			(effects
				(font
					(size 1.27 1.27)
				)
			)
		)
		(duplicate_pad_numbers_are_jumpers no)
		(fp_line
			(start 0.7874 -0.4064)
			(end 0.7874 0.4064)
			(stroke
				(width 0.1524)
				(type default)
			)
			(layer "F.SilkS")
		)
		(fp_line
			(start -0.7874 -0.4064)
			(end 0.7874 -0.4064)
			(stroke
				(width 0.1524)
				(type default)
			)
			(layer "F.SilkS")
		)
		(fp_line
			(start 0.7874 0.4064)
			(end -0.7874 0.4064)
			(stroke
				(width 0.1524)
				(type default)
			)
			(layer "F.SilkS")
		)
		(fp_line
			(start -0.7874 0.4064)
			(end -0.7874 -0.4064)
			(stroke
				(width 0.1524)
				(type default)
			)
			(layer "F.SilkS")
		)
		(fp_line
			(start -0.12065 -0.305054)
			(end -0.12065 -0.2794)
			(stroke
				(width 0.1)
				(type default)
			)
			(layer "F.Fab")
		)
		(fp_line
			(start -0.67945 -0.305054)
			(end -0.12065 -0.305054)
			(stroke
				(width 0.1)
				(type default)
			)
			(layer "F.Fab")
		)
		(fp_line
			(start 0.67945 -0.3048)
			(end 0.67945 0.3048)
			(stroke
				(width 0.1)
				(type default)
			)
			(layer "F.Fab")
		)
		(fp_line
			(start 0.12065 -0.3048)
			(end 0.67945 -0.3048)
			(stroke
				(width 0.1)
				(type default)
			)
			(layer "F.Fab")
		)
		(fp_line
			(start 0.12065 -0.2794)
			(end 0.12065 -0.3048)
			(stroke
				(width 0.1)
				(type default)
			)
			(layer "F.Fab")
		)
		(fp_line
			(start -0.12065 -0.2794)
			(end 0.12065 -0.2794)
			(stroke
				(width 0.1)
				(type default)
			)
			(layer "F.Fab")
		)
		(fp_line
			(start 0.120396 0.2794)
			(end -0.12065 0.2794)
			(stroke
				(width 0.1)
				(type default)
			)
			(layer "F.Fab")
		)
		(fp_line
			(start -0.12065 0.2794)
			(end -0.12065 0.3048)
			(stroke
				(width 0.1)
				(type default)
			)
			(layer "F.Fab")
		)
		(fp_line
			(start 0.67945 0.3048)
			(end 0.120396 0.3048)
			(stroke
				(width 0.1)
				(type default)
			)
			(layer "F.Fab")
		)
		(fp_line
			(start 0.120396 0.3048)
			(end 0.120396 0.2794)
			(stroke
				(width 0.1)
				(type default)
			)
			(layer "F.Fab")
		)
		(fp_line
			(start -0.12065 0.3048)
			(end -0.67945 0.3048)
			(stroke
				(width 0.1)
				(type default)
			)
			(layer "F.Fab")
		)
		(fp_line
			(start -0.67945 0.3048)
			(end -0.67945 -0.305054)
			(stroke
				(width 0.1)
				(type default)
			)
			(layer "F.Fab")
		)
		(pad "1" smd circle
			(at -0.40005 0 90)
			(size 0 0)
			(layers "F.Cu" "F.Mask" "F.Paste")
			(net "RST_MB_BMC_BUF_N")
		)
		(pad "2" smd circle
			(at 0.40005 0 90)
			(size 0 0)
			(layers "F.Cu" "F.Mask" "F.Paste")
			(net "RST_MB_BMC_BUF_R_N")
		)
	)
	(footprint ""
		(layer "F.Cu")
		(at 231.844596 -275.503386)
		(property "Reference" "R782"
			(at 0 0 0)
			(layer "F.SilkS")
			(hide yes)
			(effects
				(font
					(size 1.27 1.27)
				)
			)
		)
		(property "Value" ""
			(at 0 0 0)
			(layer "F.Fab")
			(effects
				(font
					(size 1.27 1.27)
				)
			)
		)
		(duplicate_pad_numbers_are_jumpers no)
		(fp_line
			(start -0.7874 -0.4064)
			(end 0.7874 -0.4064)
			(stroke
				(width 0.1524)
				(type default)
			)
			(layer "F.SilkS")
		)
		(fp_line
			(start -0.7874 0.4064)
			(end -0.7874 -0.4064)
			(stroke
				(width 0.1524)
				(type default)
			)
			(layer "F.SilkS")
		)
		(fp_line
			(start 0.7874 -0.4064)
			(end 0.7874 0.4064)
			(stroke
				(width 0.1524)
				(type default)
			)
			(layer "F.SilkS")
		)
		(fp_line
			(start 0.7874 0.4064)
			(end -0.7874 0.4064)
			(stroke
				(width 0.1524)
				(type default)
			)
			(layer "F.SilkS")
		)
		(fp_line
			(start -0.67945 -0.305054)
			(end -0.12065 -0.305054)
			(stroke
				(width 0.1)
				(type default)
			)
			(layer "F.Fab")
		)
		(fp_line
			(start -0.67945 0.3048)
			(end -0.67945 -0.305054)
			(stroke
				(width 0.1)
				(type default)
			)
			(layer "F.Fab")
		)
		(fp_line
			(start -0.12065 -0.305054)
			(end -0.12065 -0.2794)
			(stroke
				(width 0.1)
				(type default)
			)
			(layer "F.Fab")
		)
		(fp_line
			(start -0.12065 -0.2794)
			(end 0.12065 -0.2794)
			(stroke
				(width 0.1)
				(type default)
			)
			(layer "F.Fab")
		)
		(fp_line
			(start -0.12065 0.2794)
			(end -0.12065 0.3048)
			(stroke
				(width 0.1)
				(type default)
			)
			(layer "F.Fab")
		)
		(fp_line
			(start -0.12065 0.3048)
			(end -0.67945 0.3048)
			(stroke
				(width 0.1)
				(type default)
			)
			(layer "F.Fab")
		)
		(fp_line
			(start 0.120396 0.2794)
			(end -0.12065 0.2794)
			(stroke
				(width 0.1)
				(type default)
			)
			(layer "F.Fab")
		)
		(fp_line
			(start 0.120396 0.3048)
			(end 0.120396 0.2794)
			(stroke
				(width 0.1)
				(type default)
			)
			(layer "F.Fab")
		)
		(fp_line
			(start 0.12065 -0.3048)
			(end 0.67945 -0.3048)
			(stroke
				(width 0.1)
				(type default)
			)
			(layer "F.Fab")
		)
		(fp_line
			(start 0.12065 -0.2794)
			(end 0.12065 -0.3048)
			(stroke
				(width 0.1)
				(type default)
			)
			(layer "F.Fab")
		)
		(fp_line
			(start 0.67945 -0.3048)
			(end 0.67945 0.3048)
			(stroke
				(width 0.1)
				(type default)
			)
			(layer "F.Fab")
		)
		(fp_line
			(start 0.67945 0.3048)
			(end 0.120396 0.3048)
			(stroke
				(width 0.1)
				(type default)
			)
			(layer "F.Fab")
		)
		(pad "1" smd circle
			(at -0.40005 0)
			(size 0 0)
			(layers "F.Cu" "F.Mask" "F.Paste")
			(net "PEX1_P1V25_ADC_A0")
		)
		(pad "2" smd circle
			(at 0.40005 0)
			(size 0 0)
			(layers "F.Cu" "F.Mask" "F.Paste")
			(net "P3V3_AUX")
		)
	)
	(footprint ""
		(layer "F.Cu")
		(at 206.623158 -87.977472)
		(property "Reference" "R4267"
			(at 0 0 0)
			(layer "F.SilkS")
			(hide yes)
			(effects
				(font
					(size 1.27 1.27)
				)
			)
		)
		(property "Value" ""
			(at 0 0 0)
			(layer "F.Fab")
			(effects
				(font
					(size 1.27 1.27)
				)
			)
		)
		(duplicate_pad_numbers_are_jumpers no)
		(fp_line
			(start -0.7874 -0.4064)
			(end 0.7874 -0.4064)
			(stroke
				(width 0.1524)
				(type default)
			)
			(layer "F.SilkS")
		)
		(fp_line
			(start -0.7874 0.4064)
			(end -0.7874 -0.4064)
			(stroke
				(width 0.1524)
				(type default)
			)
			(layer "F.SilkS")
		)
		(fp_line
			(start 0.7874 -0.4064)
			(end 0.7874 0.4064)
			(stroke
				(width 0.1524)
				(type default)
			)
			(layer "F.SilkS")
		)
		(fp_line
			(start 0.7874 0.4064)
			(end -0.7874 0.4064)
			(stroke
				(width 0.1524)
				(type default)
			)
			(layer "F.SilkS")
		)
		(fp_line
			(start -0.67945 -0.305054)
			(end -0.12065 -0.305054)
			(stroke
				(width 0.1)
				(type default)
			)
			(layer "F.Fab")
		)
		(fp_line
			(start -0.67945 0.3048)
			(end -0.67945 -0.305054)
			(stroke
				(width 0.1)
				(type default)
			)
			(layer "F.Fab")
		)
		(fp_line
			(start -0.12065 -0.305054)
			(end -0.12065 -0.2794)
			(stroke
				(width 0.1)
				(type default)
			)
			(layer "F.Fab")
		)
		(fp_line
			(start -0.12065 -0.2794)
			(end 0.12065 -0.2794)
			(stroke
				(width 0.1)
				(type default)
			)
			(layer "F.Fab")
		)
		(fp_line
			(start -0.12065 0.2794)
			(end -0.12065 0.3048)
			(stroke
				(width 0.1)
				(type default)
			)
			(layer "F.Fab")
		)
		(fp_line
			(start -0.12065 0.3048)
			(end -0.67945 0.3048)
			(stroke
				(width 0.1)
				(type default)
			)
			(layer "F.Fab")
		)
		(fp_line
			(start 0.120396 0.2794)
			(end -0.12065 0.2794)
			(stroke
				(width 0.1)
				(type default)
			)
			(layer "F.Fab")
		)
		(fp_line
			(start 0.120396 0.3048)
			(end 0.120396 0.2794)
			(stroke
				(width 0.1)
				(type default)
			)
			(layer "F.Fab")
		)
		(fp_line
			(start 0.12065 -0.3048)
			(end 0.67945 -0.3048)
			(stroke
				(width 0.1)
				(type default)
			)
			(layer "F.Fab")
		)
		(fp_line
			(start 0.12065 -0.2794)
			(end 0.12065 -0.3048)
			(stroke
				(width 0.1)
				(type default)
			)
			(layer "F.Fab")
		)
		(fp_line
			(start 0.67945 -0.3048)
			(end 0.67945 0.3048)
			(stroke
				(width 0.1)
				(type default)
			)
			(layer "F.Fab")
		)
		(fp_line
			(start 0.67945 0.3048)
			(end 0.120396 0.3048)
			(stroke
				(width 0.1)
				(type default)
			)
			(layer "F.Fab")
		)
		(pad "1" smd circle
			(at -0.40005 0)
			(size 0 0)
			(layers "F.Cu" "F.Mask" "F.Paste")
			(net "SSD_LED_IOEXP_A1")
		)
		(pad "2" smd circle
			(at 0.40005 0)
			(size 0 0)
			(layers "F.Cu" "F.Mask" "F.Paste")
			(net "GND")
		)
	)
	(footprint ""
		(layer "F.Cu")
		(at 198.947786 -40.037258 90)
		(property "Reference" "U370"
			(at 0.399542 2.373884 90)
			(unlocked yes)
			(layer "F.SilkS")
			(effects
				(font
					(size 0.7874 0.5842)
					(thickness 0.1524)
				)
			)
		)
		(property "Value" ""
			(at 0 0 90)
			(layer "F.Fab")
			(effects
				(font
					(size 1.27 1.27)
				)
			)
		)
		(duplicate_pad_numbers_are_jumpers no)
		(fp_line
			(start -1.949958 -1.610106)
			(end 1.949958 -1.610106)
			(stroke
				(width 0.1524)
				(type default)
			)
			(layer "F.SilkS")
		)
		(fp_line
			(start 1.949958 -1.560068)
			(end 1.949958 1.610106)
			(stroke
				(width 0.1524)
				(type default)
			)
			(layer "F.SilkS")
		)
		(fp_line
			(start 1.949958 1.610106)
			(end -1.949958 1.610106)
			(stroke
				(width 0.1524)
				(type default)
			)
			(layer "F.SilkS")
		)
		(fp_line
			(start -1.949958 1.610106)
			(end -1.949958 -1.610106)
			(stroke
				(width 0.1524)
				(type default)
			)
			(layer "F.SilkS")
		)
		(fp_line
			(start 0.750062 -1.560068)
			(end 0.750062 1.560068)
			(stroke
				(width 0.1)
				(type default)
			)
			(layer "F.Fab")
		)
		(fp_line
			(start -0.750062 -1.560068)
			(end 0.750062 -1.560068)
			(stroke
				(width 0.1)
				(type default)
			)
			(layer "F.Fab")
		)
		(fp_line
			(start 0.750062 1.560068)
			(end -0.750062 1.560068)
			(stroke
				(width 0.1)
				(type default)
			)
			(layer "F.Fab")
		)
		(fp_line
			(start -0.750062 1.560068)
			(end -0.750062 -1.560068)
			(stroke
				(width 0.1)
				(type default)
			)
			(layer "F.Fab")
		)
		(pad "D" smd rect
			(at 1.100074 0)
			(size 1.016 1.4224)
			(layers "F.Cu" "F.Mask" "F.Paste")
			(net "SSD7_AUX_P3V3_EN")
		)
		(pad "G" smd rect
			(at -1.100074 -0.94996)
			(size 1.016 1.4224)
			(layers "F.Cu" "F.Mask" "F.Paste")
			(net "PRSNT_SSD7_R1_N")
		)
		(pad "S" smd rect
			(at -1.100074 0.94996)
			(size 1.016 1.4224)
			(layers "F.Cu" "F.Mask" "F.Paste")
			(net "GND")
		)
	)
)
